FILE_TYPE = MACRO_DRAWING;
SET COLOR_WIRE YELLOW;
SET COLOR_PROP ORANGE;
SET COLOR_DOT WHITE;
SET COLOR_ARC YELLOW;
SET COLOR_BODY GREEN;
SET COLOR_NOTE PURPLE;
SET PROP_DISPLAY VALUE;
SET PAGE_NUMBER P28;
FORCEADD TAP..1
(3400 3450);
FORCEPROP 3 LASTPIN (3350 3450) SIG_NAME DMI_CPU0_PCH_TX_DN<5>
J 0
(3360 3460);
DISPLAY 0.659574 (3360 3460);
PAINT MONO (3360 3460);
DISPLAY INVISIBLE (3360 3460);
FORCEPROP 1 LASTPIN (3350 3450) BN 5
J 0
(3338 3458);
DISPLAY 0.680851 (3338 3458);
PAINT GREEN (3338 3458);
FORCEPROP 2 LAST CDS_LIB standard
J 0
(3400 3450);
DISPLAY INVISIBLE (3400 3450);
FORCEPROP 1 LAST BODY_TYPE PLUMBING
J 0
(3400 3500);
DISPLAY 0.872340 (3400 3500);
PAINT GREEN (3400 3500);
DISPLAY INVISIBLE (3400 3500);
FORCEPROP 1 LAST HDL_TAP TRUE
J 0
(3725 3325);
DISPLAY 0.872340 (3725 3325);
DISPLAY INVISIBLE (3725 3325);
FORCEPROP 1 LAST PATH I151
J 0
(3398 3450);
DISPLAY 0.872340 (3398 3450);
PAINT GREEN (3398 3450);
DISPLAY INVISIBLE (3398 3450);
FORCEADD TAP..1
(3400 3400);
FORCEPROP 3 LASTPIN (3350 3400) SIG_NAME DMI_CPU0_PCH_TX_DN<4>
J 0
(3360 3410);
DISPLAY 0.659574 (3360 3410);
PAINT MONO (3360 3410);
DISPLAY INVISIBLE (3360 3410);
FORCEPROP 1 LASTPIN (3350 3400) BN 4
J 0
(3338 3408);
DISPLAY 0.680851 (3338 3408);
PAINT GREEN (3338 3408);
FORCEPROP 2 LAST CDS_LIB standard
J 0
(3400 3400);
DISPLAY INVISIBLE (3400 3400);
FORCEPROP 1 LAST BODY_TYPE PLUMBING
J 0
(3400 3450);
DISPLAY 0.872340 (3400 3450);
PAINT GREEN (3400 3450);
DISPLAY INVISIBLE (3400 3450);
FORCEPROP 1 LAST HDL_TAP TRUE
J 0
(3725 3275);
DISPLAY 0.872340 (3725 3275);
DISPLAY INVISIBLE (3725 3275);
FORCEPROP 1 LAST PATH I152
J 0
(3398 3400);
DISPLAY 0.872340 (3398 3400);
PAINT GREEN (3398 3400);
DISPLAY INVISIBLE (3398 3400);
FORCEADD TAP..1
(3150 3850);
FORCEPROP 3 LASTPIN (3100 3850) SIG_NAME DMI_CPU0_PCH_TX_DP<4>
J 0
(3110 3860);
DISPLAY 0.659574 (3110 3860);
PAINT MONO (3110 3860);
DISPLAY INVISIBLE (3110 3860);
FORCEPROP 1 LASTPIN (3100 3850) BN 4
J 0
(3088 3858);
DISPLAY 0.680851 (3088 3858);
PAINT GREEN (3088 3858);
FORCEPROP 2 LAST CDS_LIB standard
J 0
(3150 3850);
DISPLAY INVISIBLE (3150 3850);
FORCEPROP 1 LAST BODY_TYPE PLUMBING
J 0
(3150 3900);
DISPLAY 0.872340 (3150 3900);
PAINT GREEN (3150 3900);
DISPLAY INVISIBLE (3150 3900);
FORCEPROP 1 LAST HDL_TAP TRUE
J 0
(3475 3725);
DISPLAY 0.872340 (3475 3725);
DISPLAY INVISIBLE (3475 3725);
FORCEPROP 1 LAST PATH I161
J 0
(3148 3850);
DISPLAY 0.872340 (3148 3850);
PAINT GREEN (3148 3850);
DISPLAY INVISIBLE (3148 3850);
FORCEADD TAP..1
(3150 3900);
FORCEPROP 3 LASTPIN (3100 3900) SIG_NAME DMI_CPU0_PCH_TX_DP<5>
J 0
(3110 3910);
DISPLAY 0.659574 (3110 3910);
PAINT MONO (3110 3910);
DISPLAY INVISIBLE (3110 3910);
FORCEPROP 1 LASTPIN (3100 3900) BN 5
J 0
(3088 3908);
DISPLAY 0.680851 (3088 3908);
PAINT GREEN (3088 3908);
FORCEPROP 2 LAST CDS_LIB standard
J 0
(3150 3900);
DISPLAY INVISIBLE (3150 3900);
FORCEPROP 1 LAST BODY_TYPE PLUMBING
J 0
(3150 3950);
DISPLAY 0.872340 (3150 3950);
PAINT GREEN (3150 3950);
DISPLAY INVISIBLE (3150 3950);
FORCEPROP 1 LAST HDL_TAP TRUE
J 0
(3475 3775);
DISPLAY 0.872340 (3475 3775);
DISPLAY INVISIBLE (3475 3775);
FORCEPROP 1 LAST PATH I165
J 0
(3148 3900);
DISPLAY 0.872340 (3148 3900);
PAINT GREEN (3148 3900);
DISPLAY INVISIBLE (3148 3900);
FORCEADD SOCKET4677_AZIF0045P001C01CS..16
(1475 3600);
FORCEPROP 1 LAST PART_NUMBER DGA^7000023
J 0
(425 4250);
DISPLAY 0.723404 (425 4250);
PAINT GREEN (425 4250);
DISPLAY INVISIBLE (425 4250);
FORCEPROP 2 LAST VALUE SOCKET4677_AZIF0045-P001C01CS
J 0
(425 4375);
DISPLAY 1.021277 (425 4375);
FORCEPROP 1 LAST MATERIAL IO
J 0
(425 4175);
DISPLAY 0.723404 (425 4175);
PAINT GREEN (425 4175);
FORCEPROP 2 LAST PART_TYPE SMLF
J 0
(425 4425);
DISPLAY 1.021277 (425 4425);
FORCEPROP 1 LAST $LOCATION U2
J 0
(425 4325);
DISPLAY 0.723404 (425 4325);
PAINT GREEN (425 4325);
FORCEPROP 0 LASTPIN (275 3200) $PN BB18
J 2
(265 3210);
DISPLAY 0.680851 (265 3210);
PAINT MONO (265 3210);
FORCEPROP 0 LASTPIN (275 3250) $PN BE17
J 2
(265 3260);
DISPLAY 0.680851 (265 3260);
PAINT MONO (265 3260);
FORCEPROP 0 LASTPIN (275 3300) $PN BF18
J 2
(265 3310);
DISPLAY 0.680851 (265 3310);
PAINT MONO (265 3310);
FORCEPROP 0 LASTPIN (275 3350) $PN BJ17
J 2
(265 3360);
DISPLAY 0.680851 (265 3360);
PAINT MONO (265 3360);
FORCEPROP 0 LASTPIN (275 3400) $PN BK18
J 2
(265 3410);
DISPLAY 0.680851 (265 3410);
PAINT MONO (265 3410);
FORCEPROP 0 LASTPIN (275 3450) $PN BN17
J 2
(265 3460);
DISPLAY 0.680851 (265 3460);
PAINT MONO (265 3460);
FORCEPROP 0 LASTPIN (275 3500) $PN BP18
J 2
(265 3510);
DISPLAY 0.680851 (265 3510);
PAINT MONO (265 3510);
FORCEPROP 0 LASTPIN (275 3550) $PN BU17
J 2
(265 3560);
DISPLAY 0.680851 (265 3560);
PAINT MONO (265 3560);
FORCEPROP 0 LASTPIN (275 3650) $PN BC19
J 2
(265 3660);
DISPLAY 0.680851 (265 3660);
PAINT MONO (265 3660);
FORCEPROP 0 LASTPIN (275 3700) $PN BD18
J 2
(265 3710);
DISPLAY 0.680851 (265 3710);
PAINT MONO (265 3710);
FORCEPROP 0 LASTPIN (275 3750) $PN BG19
J 2
(265 3760);
DISPLAY 0.680851 (265 3760);
PAINT MONO (265 3760);
FORCEPROP 0 LASTPIN (275 3800) $PN BH18
J 2
(265 3810);
DISPLAY 0.680851 (265 3810);
PAINT MONO (265 3810);
FORCEPROP 0 LASTPIN (275 3850) $PN BL19
J 2
(265 3860);
DISPLAY 0.680851 (265 3860);
PAINT MONO (265 3860);
FORCEPROP 0 LASTPIN (275 3900) $PN BM18
J 2
(265 3910);
DISPLAY 0.680851 (265 3910);
PAINT MONO (265 3910);
FORCEPROP 0 LASTPIN (275 3950) $PN BR19
J 2
(265 3960);
DISPLAY 0.680851 (265 3960);
PAINT MONO (265 3960);
FORCEPROP 0 LASTPIN (275 4000) $PN BT18
J 2
(265 4010);
DISPLAY 0.680851 (265 4010);
PAINT MONO (265 4010);
FORCEPROP 0 LASTPIN (2675 3200) $PN BW19
J 0
(2685 3210);
DISPLAY 0.680851 (2685 3210);
PAINT MONO (2685 3210);
FORCEPROP 0 LASTPIN (2675 3250) $PN CA17
J 0
(2685 3260);
DISPLAY 0.680851 (2685 3260);
PAINT MONO (2685 3260);
FORCEPROP 0 LASTPIN (2675 3300) $PN CB18
J 0
(2685 3310);
DISPLAY 0.680851 (2685 3310);
PAINT MONO (2685 3310);
FORCEPROP 0 LASTPIN (2675 3350) $PN CE17
J 0
(2685 3360);
DISPLAY 0.680851 (2685 3360);
PAINT MONO (2685 3360);
FORCEPROP 0 LASTPIN (2675 3400) $PN CF18
J 0
(2685 3410);
DISPLAY 0.680851 (2685 3410);
PAINT MONO (2685 3410);
FORCEPROP 0 LASTPIN (2675 3450) $PN CJ17
J 0
(2685 3460);
DISPLAY 0.680851 (2685 3460);
PAINT MONO (2685 3460);
FORCEPROP 0 LASTPIN (2675 3500) $PN CK18
J 0
(2685 3510);
DISPLAY 0.680851 (2685 3510);
PAINT MONO (2685 3510);
FORCEPROP 0 LASTPIN (2675 3550) $PN CN17
J 0
(2685 3560);
DISPLAY 0.680851 (2685 3560);
PAINT MONO (2685 3560);
FORCEPROP 0 LASTPIN (2675 3650) $PN CA19
J 0
(2685 3660);
DISPLAY 0.680851 (2685 3660);
PAINT MONO (2685 3660);
FORCEPROP 0 LASTPIN (2675 3700) $PN BY18
J 0
(2685 3710);
DISPLAY 0.680851 (2685 3710);
PAINT MONO (2685 3710);
FORCEPROP 0 LASTPIN (2675 3750) $PN CC19
J 0
(2685 3760);
DISPLAY 0.680851 (2685 3760);
PAINT MONO (2685 3760);
FORCEPROP 0 LASTPIN (2675 3800) $PN CD18
J 0
(2685 3810);
DISPLAY 0.680851 (2685 3810);
PAINT MONO (2685 3810);
FORCEPROP 0 LASTPIN (2675 3850) $PN CG19
J 0
(2685 3860);
DISPLAY 0.680851 (2685 3860);
PAINT MONO (2685 3860);
FORCEPROP 0 LASTPIN (2675 3900) $PN CH18
J 0
(2685 3910);
DISPLAY 0.680851 (2685 3910);
PAINT MONO (2685 3910);
FORCEPROP 0 LASTPIN (2675 3950) $PN CL19
J 0
(2685 3960);
DISPLAY 0.680851 (2685 3960);
PAINT MONO (2685 3960);
FORCEPROP 0 LASTPIN (2675 4000) $PN CM18
J 0
(2685 4010);
DISPLAY 0.680851 (2685 4010);
PAINT MONO (2685 4010);
FORCEPROP 1 LAST CDS_LMAN_SYM_OUTLINE -1050,550,1050,-550
J 0
(1475 3600);
DISPLAY 0.468085 (1475 3600);
PAINT GREEN (1475 3600);
DISPLAY INVISIBLE (1475 3600);
FORCEPROP 1 LAST NEEDS_NO_SIZE TRUE
J 0
(1475 3600);
DISPLAY 0.723404 (1475 3600);
PAINT GREEN (1475 3600);
DISPLAY INVISIBLE (1475 3600);
FORCEPROP 2 LAST CDS_LIB pure_quanta
J 0
(1475 3600);
DISPLAY INVISIBLE (1475 3600);
FORCEPROP 2 LAST CDS_LOCATION U2
J 0
(425 4475);
DISPLAY 1.021277 (425 4475);
DISPLAY INVISIBLE (425 4475);
FORCEPROP 0 LAST $SEC 16
J 0
(425 4475);
DISPLAY 0.680851 (425 4475);
PAINT MONO (425 4475);
DISPLAY INVISIBLE (425 4475);
FORCEPROP 2 LAST CDS_SEC 16
J 0
(425 4475);
DISPLAY 1.021277 (425 4475);
DISPLAY INVISIBLE (425 4475);
FORCEPROP 1 LAST PATH I169
J 0
(1475 3600);
DISPLAY 0.723404 (1475 3600);
PAINT GREEN (1475 3600);
DISPLAY INVISIBLE (1475 3600);
FORCEADD TAP..1
R 2
(-475 3300);
FORCEPROP 3 LASTPIN (-425 3300) SIG_NAME DMI_CPU0_PCH_RX_C_DN<2>
J 0
(-415 3310);
DISPLAY 0.659574 (-415 3310);
PAINT MONO (-415 3310);
DISPLAY INVISIBLE (-415 3310);
FORCEPROP 1 LASTPIN (-425 3300) BN 2
J 2
(-413 3308);
DISPLAY 0.680851 (-413 3308);
PAINT GREEN (-413 3308);
FORCEPROP 2 LAST CDS_LIB standard
J 0
(-475 3300);
DISPLAY INVISIBLE (-475 3300);
FORCEPROP 1 LAST BODY_TYPE PLUMBING
J 2
(-475 3350);
DISPLAY 0.872340 (-475 3350);
PAINT GREEN (-475 3350);
DISPLAY INVISIBLE (-475 3350);
FORCEPROP 1 LAST HDL_TAP TRUE
J 2
(-800 3175);
DISPLAY 0.872340 (-800 3175);
DISPLAY INVISIBLE (-800 3175);
FORCEPROP 1 LAST PATH I171
J 2
(-473 3300);
DISPLAY 0.872340 (-473 3300);
PAINT GREEN (-473 3300);
DISPLAY INVISIBLE (-473 3300);
FORCEADD TAP..1
R 2
(-475 3200);
FORCEPROP 3 LASTPIN (-425 3200) SIG_NAME DMI_CPU0_PCH_RX_C_DN<0>
J 0
(-415 3210);
DISPLAY 0.659574 (-415 3210);
PAINT MONO (-415 3210);
DISPLAY INVISIBLE (-415 3210);
FORCEPROP 1 LASTPIN (-425 3200) BN 0
J 2
(-413 3208);
DISPLAY 0.680851 (-413 3208);
PAINT GREEN (-413 3208);
FORCEPROP 2 LAST CDS_LIB standard
J 0
(-475 3200);
DISPLAY INVISIBLE (-475 3200);
FORCEPROP 1 LAST BODY_TYPE PLUMBING
J 2
(-475 3250);
DISPLAY 0.872340 (-475 3250);
PAINT GREEN (-475 3250);
DISPLAY INVISIBLE (-475 3250);
FORCEPROP 1 LAST HDL_TAP TRUE
J 2
(-800 3075);
DISPLAY 0.872340 (-800 3075);
DISPLAY INVISIBLE (-800 3075);
FORCEPROP 1 LAST PATH I173
J 2
(-473 3200);
DISPLAY 0.872340 (-473 3200);
PAINT GREEN (-473 3200);
DISPLAY INVISIBLE (-473 3200);
FORCEADD TAP..1
R 2
(-225 4000);
FORCEPROP 3 LASTPIN (-175 4000) SIG_NAME DMI_CPU0_PCH_RX_C_DP<7>
J 0
(-165 4010);
DISPLAY 0.659574 (-165 4010);
PAINT MONO (-165 4010);
DISPLAY INVISIBLE (-165 4010);
FORCEPROP 1 LASTPIN (-175 4000) BN 7
J 2
(-163 4008);
DISPLAY 0.680851 (-163 4008);
PAINT GREEN (-163 4008);
FORCEPROP 2 LAST CDS_LIB standard
J 0
(-225 4000);
DISPLAY INVISIBLE (-225 4000);
FORCEPROP 1 LAST BODY_TYPE PLUMBING
J 2
(-225 4050);
DISPLAY 0.872340 (-225 4050);
PAINT GREEN (-225 4050);
DISPLAY INVISIBLE (-225 4050);
FORCEPROP 1 LAST HDL_TAP TRUE
J 2
(-550 3875);
DISPLAY 0.872340 (-550 3875);
DISPLAY INVISIBLE (-550 3875);
FORCEPROP 1 LAST PATH I179
J 2
(-223 4000);
DISPLAY 0.872340 (-223 4000);
PAINT GREEN (-223 4000);
DISPLAY INVISIBLE (-223 4000);
FORCEADD TAP..1
R 2
(-225 3750);
FORCEPROP 3 LASTPIN (-175 3750) SIG_NAME DMI_CPU0_PCH_RX_C_DP<2>
J 0
(-165 3760);
DISPLAY 0.659574 (-165 3760);
PAINT MONO (-165 3760);
DISPLAY INVISIBLE (-165 3760);
FORCEPROP 1 LASTPIN (-175 3750) BN 2
J 2
(-163 3758);
DISPLAY 0.680851 (-163 3758);
PAINT GREEN (-163 3758);
FORCEPROP 2 LAST CDS_LIB standard
J 0
(-225 3750);
DISPLAY INVISIBLE (-225 3750);
FORCEPROP 1 LAST BODY_TYPE PLUMBING
J 2
(-225 3800);
DISPLAY 0.872340 (-225 3800);
PAINT GREEN (-225 3800);
DISPLAY INVISIBLE (-225 3800);
FORCEPROP 1 LAST HDL_TAP TRUE
J 2
(-550 3625);
DISPLAY 0.872340 (-550 3625);
DISPLAY INVISIBLE (-550 3625);
FORCEPROP 1 LAST PATH I184
J 2
(-223 3750);
DISPLAY 0.872340 (-223 3750);
PAINT GREEN (-223 3750);
DISPLAY INVISIBLE (-223 3750);
FORCEADD TAP..1
R 2
(-225 3650);
FORCEPROP 3 LASTPIN (-175 3650) SIG_NAME DMI_CPU0_PCH_RX_C_DP<0>
J 0
(-165 3660);
DISPLAY 0.659574 (-165 3660);
PAINT MONO (-165 3660);
DISPLAY INVISIBLE (-165 3660);
FORCEPROP 1 LASTPIN (-175 3650) BN 0
J 2
(-163 3658);
DISPLAY 0.680851 (-163 3658);
PAINT GREEN (-163 3658);
FORCEPROP 2 LAST CDS_LIB standard
J 0
(-225 3650);
DISPLAY INVISIBLE (-225 3650);
FORCEPROP 1 LAST BODY_TYPE PLUMBING
J 2
(-225 3700);
DISPLAY 0.872340 (-225 3700);
PAINT GREEN (-225 3700);
DISPLAY INVISIBLE (-225 3700);
FORCEPROP 1 LAST HDL_TAP TRUE
J 2
(-550 3525);
DISPLAY 0.872340 (-550 3525);
DISPLAY INVISIBLE (-550 3525);
FORCEPROP 1 LAST PATH I186
J 2
(-223 3650);
DISPLAY 0.872340 (-223 3650);
PAINT GREEN (-223 3650);
DISPLAY INVISIBLE (-223 3650);
FORCEADD TAP..1
R 2
(-475 3550);
FORCEPROP 3 LASTPIN (-425 3550) SIG_NAME DMI_CPU0_PCH_RX_C_DN<7>
J 0
(-415 3560);
DISPLAY 0.659574 (-415 3560);
PAINT MONO (-415 3560);
DISPLAY INVISIBLE (-415 3560);
FORCEPROP 1 LASTPIN (-425 3550) BN 7
J 2
(-413 3558);
DISPLAY 0.680851 (-413 3558);
PAINT GREEN (-413 3558);
FORCEPROP 2 LAST CDS_LIB standard
J 0
(-475 3550);
DISPLAY INVISIBLE (-475 3550);
FORCEPROP 1 LAST BODY_TYPE PLUMBING
J 2
(-475 3600);
DISPLAY 0.872340 (-475 3600);
PAINT GREEN (-475 3600);
DISPLAY INVISIBLE (-475 3600);
FORCEPROP 1 LAST HDL_TAP TRUE
J 2
(-800 3425);
DISPLAY 0.872340 (-800 3425);
DISPLAY INVISIBLE (-800 3425);
FORCEPROP 1 LAST PATH I188
J 2
(-473 3550);
DISPLAY 0.872340 (-473 3550);
PAINT GREEN (-473 3550);
DISPLAY INVISIBLE (-473 3550);
FORCEADD OFFPAGE..1
(-1750 4150);
FORCEPROP 2 LAST $XR0 178 
J 0
(-2032 4150);
DISPLAY 0.638298 (-2032 4150);
PAINT MONO (-2032 4150);
FORCEPROP 2 LAST CDS_LIB standard
J 0
(-1750 4150);
PAINT MONO (-1750 4150);
DISPLAY INVISIBLE (-1750 4150);
FORCEPROP 1 LAST OFFPAGE TRUE
J 0
(-1425 4025);
DISPLAY 0.872340 (-1425 4025);
DISPLAY INVISIBLE (-1425 4025);
FORCEPROP 1 LAST COMMENT_BODY TRUE
J 0
(-1625 4050);
DISPLAY 0.872340 (-1625 4050);
PAINT GREEN (-1625 4050);
DISPLAY INVISIBLE (-1625 4050);
FORCEPROP 2 LAST PATH I281
J 0
(-1700 4225);
DISPLAY 1.021277 (-1700 4225);
DISPLAY INVISIBLE (-1700 4225);
FORCEADD OFFPAGE..1
(-1750 4100);
FORCEPROP 2 LAST $XR0 178 
J 0
(-2032 4100);
DISPLAY 0.638298 (-2032 4100);
PAINT MONO (-2032 4100);
FORCEPROP 2 LAST CDS_LIB standard
J 0
(-1750 4100);
PAINT MONO (-1750 4100);
DISPLAY INVISIBLE (-1750 4100);
FORCEPROP 1 LAST OFFPAGE TRUE
J 0
(-1425 3975);
DISPLAY 0.872340 (-1425 3975);
DISPLAY INVISIBLE (-1425 3975);
FORCEPROP 1 LAST COMMENT_BODY TRUE
J 0
(-1625 4000);
DISPLAY 0.872340 (-1625 4000);
PAINT GREEN (-1625 4000);
DISPLAY INVISIBLE (-1625 4000);
FORCEPROP 2 LAST PATH I282
J 0
(-1700 4175);
DISPLAY 1.021277 (-1700 4175);
DISPLAY INVISIBLE (-1700 4175);
FORCEADD OFFPAGE..2
(4500 4100);
FORCEPROP 2 LAST $XR0 178 
J 0
(4689 4100);
DISPLAY 0.638298 (4689 4100);
PAINT MONO (4689 4100);
FORCEPROP 2 LAST CDS_LIB standard
J 0
(4500 4100);
PAINT MONO (4500 4100);
DISPLAY INVISIBLE (4500 4100);
FORCEPROP 1 LAST OFFPAGE TRUE
J 0
(4825 3975);
DISPLAY 1.170213 (4825 3975);
PAINT GREEN (4825 3975);
DISPLAY INVISIBLE (4825 3975);
FORCEPROP 1 LAST COMMENT_BODY TRUE
J 0
(4455 4005);
DISPLAY 1.170213 (4455 4005);
PAINT GREEN (4455 4005);
DISPLAY INVISIBLE (4455 4005);
FORCEPROP 2 LAST PATH I286
J 0
(4675 4175);
DISPLAY 1.021277 (4675 4175);
DISPLAY INVISIBLE (4675 4175);
FORCEADD OFFPAGE..2
(4500 4050);
FORCEPROP 2 LAST $XR0 178 
J 0
(4689 4050);
DISPLAY 0.638298 (4689 4050);
PAINT MONO (4689 4050);
FORCEPROP 2 LAST CDS_LIB standard
J 0
(4500 4050);
PAINT MONO (4500 4050);
DISPLAY INVISIBLE (4500 4050);
FORCEPROP 1 LAST OFFPAGE TRUE
J 0
(4825 3925);
DISPLAY 1.170213 (4825 3925);
PAINT GREEN (4825 3925);
DISPLAY INVISIBLE (4825 3925);
FORCEPROP 1 LAST COMMENT_BODY TRUE
J 0
(4455 3955);
DISPLAY 1.170213 (4455 3955);
PAINT GREEN (4455 3955);
DISPLAY INVISIBLE (4455 3955);
FORCEPROP 2 LAST PATH I287
J 0
(4675 4125);
DISPLAY 1.021277 (4675 4125);
DISPLAY INVISIBLE (4675 4125);
FORCEADD TAP..1
(3400 3650);
FORCEPROP 3 LASTPIN (3350 3650) SIG_NAME DMI_CPU0_PCH_TX_DN<0>
J 0
(3360 3660);
DISPLAY 0.659574 (3360 3660);
PAINT MONO (3360 3660);
DISPLAY INVISIBLE (3360 3660);
FORCEPROP 1 LASTPIN (3350 3650) BN 0
J 0
(3338 3658);
DISPLAY 0.680851 (3338 3658);
PAINT GREEN (3338 3658);
FORCEPROP 2 LAST CDS_LIB standard
J 0
(3400 3650);
DISPLAY INVISIBLE (3400 3650);
FORCEPROP 1 LAST BODY_TYPE PLUMBING
J 0
(3400 3700);
DISPLAY 0.872340 (3400 3700);
PAINT GREEN (3400 3700);
DISPLAY INVISIBLE (3400 3700);
FORCEPROP 1 LAST HDL_TAP TRUE
J 0
(3725 3525);
DISPLAY 0.872340 (3725 3525);
DISPLAY INVISIBLE (3725 3525);
FORCEPROP 1 LAST PATH I288
J 0
(3398 3650);
DISPLAY 0.872340 (3398 3650);
PAINT GREEN (3398 3650);
DISPLAY INVISIBLE (3398 3650);
FORCEADD TAP..1
(3400 3700);
FORCEPROP 3 LASTPIN (3350 3700) SIG_NAME DMI_CPU0_PCH_TX_DN<1>
J 0
(3360 3710);
DISPLAY 0.659574 (3360 3710);
PAINT MONO (3360 3710);
DISPLAY INVISIBLE (3360 3710);
FORCEPROP 1 LASTPIN (3350 3700) BN 1
J 0
(3338 3708);
DISPLAY 0.680851 (3338 3708);
PAINT GREEN (3338 3708);
FORCEPROP 2 LAST CDS_LIB standard
J 0
(3400 3700);
DISPLAY INVISIBLE (3400 3700);
FORCEPROP 1 LAST BODY_TYPE PLUMBING
J 0
(3400 3750);
DISPLAY 0.872340 (3400 3750);
PAINT GREEN (3400 3750);
DISPLAY INVISIBLE (3400 3750);
FORCEPROP 1 LAST HDL_TAP TRUE
J 0
(3725 3575);
DISPLAY 0.872340 (3725 3575);
DISPLAY INVISIBLE (3725 3575);
FORCEPROP 1 LAST PATH I289
J 0
(3398 3700);
DISPLAY 0.872340 (3398 3700);
PAINT GREEN (3398 3700);
DISPLAY INVISIBLE (3398 3700);
FORCEADD TAP..1
(3400 3750);
FORCEPROP 3 LASTPIN (3350 3750) SIG_NAME DMI_CPU0_PCH_TX_DN<2>
J 0
(3360 3760);
DISPLAY 0.659574 (3360 3760);
PAINT MONO (3360 3760);
DISPLAY INVISIBLE (3360 3760);
FORCEPROP 1 LASTPIN (3350 3750) BN 2
J 0
(3338 3758);
DISPLAY 0.680851 (3338 3758);
PAINT GREEN (3338 3758);
FORCEPROP 2 LAST CDS_LIB standard
J 0
(3400 3750);
DISPLAY INVISIBLE (3400 3750);
FORCEPROP 1 LAST BODY_TYPE PLUMBING
J 0
(3400 3800);
DISPLAY 0.872340 (3400 3800);
PAINT GREEN (3400 3800);
DISPLAY INVISIBLE (3400 3800);
FORCEPROP 1 LAST HDL_TAP TRUE
J 0
(3725 3625);
DISPLAY 0.872340 (3725 3625);
DISPLAY INVISIBLE (3725 3625);
FORCEPROP 1 LAST PATH I290
J 0
(3398 3750);
DISPLAY 0.872340 (3398 3750);
PAINT GREEN (3398 3750);
DISPLAY INVISIBLE (3398 3750);
FORCEADD TAP..1
(3400 4000);
FORCEPROP 3 LASTPIN (3350 4000) SIG_NAME DMI_CPU0_PCH_TX_DN<7>
J 0
(3360 4010);
DISPLAY 0.659574 (3360 4010);
PAINT MONO (3360 4010);
DISPLAY INVISIBLE (3360 4010);
FORCEPROP 1 LASTPIN (3350 4000) BN 7
J 0
(3338 4008);
DISPLAY 0.680851 (3338 4008);
PAINT GREEN (3338 4008);
FORCEPROP 2 LAST CDS_LIB standard
J 0
(3400 4000);
DISPLAY INVISIBLE (3400 4000);
FORCEPROP 1 LAST BODY_TYPE PLUMBING
J 0
(3400 4050);
DISPLAY 0.872340 (3400 4050);
PAINT GREEN (3400 4050);
DISPLAY INVISIBLE (3400 4050);
FORCEPROP 1 LAST HDL_TAP TRUE
J 0
(3725 3875);
DISPLAY 0.872340 (3725 3875);
DISPLAY INVISIBLE (3725 3875);
FORCEPROP 1 LAST PATH I292
J 0
(3398 4000);
DISPLAY 0.872340 (3398 4000);
PAINT GREEN (3398 4000);
DISPLAY INVISIBLE (3398 4000);
FORCEADD TAP..1
(3150 3250);
FORCEPROP 3 LASTPIN (3100 3250) SIG_NAME DMI_CPU0_PCH_TX_DP<1>
J 0
(3110 3260);
DISPLAY 0.659574 (3110 3260);
PAINT MONO (3110 3260);
DISPLAY INVISIBLE (3110 3260);
FORCEPROP 1 LASTPIN (3100 3250) BN 1
J 0
(3088 3258);
DISPLAY 0.680851 (3088 3258);
PAINT GREEN (3088 3258);
FORCEPROP 2 LAST CDS_LIB standard
J 0
(3150 3250);
DISPLAY INVISIBLE (3150 3250);
FORCEPROP 1 LAST BODY_TYPE PLUMBING
J 0
(3150 3300);
DISPLAY 0.872340 (3150 3300);
PAINT GREEN (3150 3300);
DISPLAY INVISIBLE (3150 3300);
FORCEPROP 1 LAST HDL_TAP TRUE
J 0
(3475 3125);
DISPLAY 0.872340 (3475 3125);
DISPLAY INVISIBLE (3475 3125);
FORCEPROP 1 LAST PATH I293
J 0
(3148 3250);
DISPLAY 0.872340 (3148 3250);
PAINT GREEN (3148 3250);
DISPLAY INVISIBLE (3148 3250);
FORCEADD TAP..1
(3150 3300);
FORCEPROP 3 LASTPIN (3100 3300) SIG_NAME DMI_CPU0_PCH_TX_DP<2>
J 0
(3110 3310);
DISPLAY 0.659574 (3110 3310);
PAINT MONO (3110 3310);
DISPLAY INVISIBLE (3110 3310);
FORCEPROP 1 LASTPIN (3100 3300) BN 2
J 0
(3088 3308);
DISPLAY 0.680851 (3088 3308);
PAINT GREEN (3088 3308);
FORCEPROP 2 LAST CDS_LIB standard
J 0
(3150 3300);
DISPLAY INVISIBLE (3150 3300);
FORCEPROP 1 LAST BODY_TYPE PLUMBING
J 0
(3150 3350);
DISPLAY 0.872340 (3150 3350);
PAINT GREEN (3150 3350);
DISPLAY INVISIBLE (3150 3350);
FORCEPROP 1 LAST HDL_TAP TRUE
J 0
(3475 3175);
DISPLAY 0.872340 (3475 3175);
DISPLAY INVISIBLE (3475 3175);
FORCEPROP 1 LAST PATH I294
J 0
(3148 3300);
DISPLAY 0.872340 (3148 3300);
PAINT GREEN (3148 3300);
DISPLAY INVISIBLE (3148 3300);
FORCEADD TAP..1
(3150 3550);
FORCEPROP 3 LASTPIN (3100 3550) SIG_NAME DMI_CPU0_PCH_TX_DP<7>
J 0
(3110 3560);
DISPLAY 0.659574 (3110 3560);
PAINT MONO (3110 3560);
DISPLAY INVISIBLE (3110 3560);
FORCEPROP 1 LASTPIN (3100 3550) BN 7
J 0
(3088 3558);
DISPLAY 0.680851 (3088 3558);
PAINT GREEN (3088 3558);
FORCEPROP 2 LAST CDS_LIB standard
J 0
(3150 3550);
DISPLAY INVISIBLE (3150 3550);
FORCEPROP 1 LAST BODY_TYPE PLUMBING
J 0
(3150 3600);
DISPLAY 0.872340 (3150 3600);
PAINT GREEN (3150 3600);
DISPLAY INVISIBLE (3150 3600);
FORCEPROP 1 LAST HDL_TAP TRUE
J 0
(3475 3425);
DISPLAY 0.872340 (3475 3425);
DISPLAY INVISIBLE (3475 3425);
FORCEPROP 1 LAST PATH I296
J 0
(3148 3550);
DISPLAY 0.872340 (3148 3550);
PAINT GREEN (3148 3550);
DISPLAY INVISIBLE (3148 3550);
FORCEADD TAP..1
(3150 3200);
FORCEPROP 3 LASTPIN (3100 3200) SIG_NAME DMI_CPU0_PCH_TX_DP<0>
J 0
(3110 3210);
DISPLAY 0.659574 (3110 3210);
PAINT MONO (3110 3210);
DISPLAY INVISIBLE (3110 3210);
FORCEPROP 1 LASTPIN (3100 3200) BN 0
J 0
(3088 3208);
DISPLAY 0.680851 (3088 3208);
PAINT GREEN (3088 3208);
FORCEPROP 2 LAST CDS_LIB standard
J 0
(3150 3200);
DISPLAY INVISIBLE (3150 3200);
FORCEPROP 1 LAST BODY_TYPE PLUMBING
J 0
(3150 3250);
DISPLAY 0.872340 (3150 3250);
PAINT GREEN (3150 3250);
DISPLAY INVISIBLE (3150 3250);
FORCEPROP 1 LAST HDL_TAP TRUE
J 0
(3475 3075);
DISPLAY 0.872340 (3475 3075);
DISPLAY INVISIBLE (3475 3075);
FORCEPROP 1 LAST PATH I297
J 0
(3148 3200);
DISPLAY 0.872340 (3148 3200);
PAINT GREEN (3148 3200);
DISPLAY INVISIBLE (3148 3200);
FORCEADD TAP..1
R 2
(-475 3950);
FORCEPROP 3 LASTPIN (-425 3950) SIG_NAME DMI_CPU0_PCH_RX_C_DN<6>
J 0
(-415 3960);
DISPLAY 0.659574 (-415 3960);
PAINT MONO (-415 3960);
DISPLAY INVISIBLE (-415 3960);
FORCEPROP 1 LASTPIN (-425 3950) BN 6
J 2
(-413 3958);
DISPLAY 0.680851 (-413 3958);
PAINT GREEN (-413 3958);
FORCEPROP 2 LAST CDS_LIB standard
J 0
(-475 3950);
DISPLAY INVISIBLE (-475 3950);
FORCEPROP 1 LAST BODY_TYPE PLUMBING
J 2
(-475 4000);
DISPLAY 0.872340 (-475 4000);
PAINT GREEN (-475 4000);
DISPLAY INVISIBLE (-475 4000);
FORCEPROP 1 LAST HDL_TAP TRUE
J 2
(-800 3825);
DISPLAY 0.872340 (-800 3825);
DISPLAY INVISIBLE (-800 3825);
FORCEPROP 1 LAST PATH I298
J 2
(-473 3950);
DISPLAY 0.872340 (-473 3950);
PAINT GREEN (-473 3950);
DISPLAY INVISIBLE (-473 3950);
FORCEADD TAP..1
R 2
(-475 3900);
FORCEPROP 3 LASTPIN (-425 3900) SIG_NAME DMI_CPU0_PCH_RX_C_DN<5>
J 0
(-415 3910);
DISPLAY 0.659574 (-415 3910);
PAINT MONO (-415 3910);
DISPLAY INVISIBLE (-415 3910);
FORCEPROP 1 LASTPIN (-425 3900) BN 5
J 2
(-413 3908);
DISPLAY 0.680851 (-413 3908);
PAINT GREEN (-413 3908);
FORCEPROP 2 LAST CDS_LIB standard
J 0
(-475 3900);
DISPLAY INVISIBLE (-475 3900);
FORCEPROP 1 LAST BODY_TYPE PLUMBING
J 2
(-475 3950);
DISPLAY 0.872340 (-475 3950);
PAINT GREEN (-475 3950);
DISPLAY INVISIBLE (-475 3950);
FORCEPROP 1 LAST HDL_TAP TRUE
J 2
(-800 3775);
DISPLAY 0.872340 (-800 3775);
DISPLAY INVISIBLE (-800 3775);
FORCEPROP 1 LAST PATH I299
J 2
(-473 3900);
DISPLAY 0.872340 (-473 3900);
PAINT GREEN (-473 3900);
DISPLAY INVISIBLE (-473 3900);
FORCEADD TAP..1
R 2
(-475 3850);
FORCEPROP 3 LASTPIN (-425 3850) SIG_NAME DMI_CPU0_PCH_RX_C_DN<4>
J 0
(-415 3860);
DISPLAY 0.659574 (-415 3860);
PAINT MONO (-415 3860);
DISPLAY INVISIBLE (-415 3860);
FORCEPROP 1 LASTPIN (-425 3850) BN 4
J 2
(-413 3858);
DISPLAY 0.680851 (-413 3858);
PAINT GREEN (-413 3858);
FORCEPROP 2 LAST CDS_LIB standard
J 0
(-475 3850);
DISPLAY INVISIBLE (-475 3850);
FORCEPROP 1 LAST BODY_TYPE PLUMBING
J 2
(-475 3900);
DISPLAY 0.872340 (-475 3900);
PAINT GREEN (-475 3900);
DISPLAY INVISIBLE (-475 3900);
FORCEPROP 1 LAST HDL_TAP TRUE
J 2
(-800 3725);
DISPLAY 0.872340 (-800 3725);
DISPLAY INVISIBLE (-800 3725);
FORCEPROP 1 LAST PATH I300
J 2
(-473 3850);
DISPLAY 0.872340 (-473 3850);
PAINT GREEN (-473 3850);
DISPLAY INVISIBLE (-473 3850);
FORCEADD TAP..1
R 2
(-475 3800);
FORCEPROP 3 LASTPIN (-425 3800) SIG_NAME DMI_CPU0_PCH_RX_C_DN<3>
J 0
(-415 3810);
DISPLAY 0.659574 (-415 3810);
PAINT MONO (-415 3810);
DISPLAY INVISIBLE (-415 3810);
FORCEPROP 1 LASTPIN (-425 3800) BN 3
J 2
(-413 3808);
DISPLAY 0.680851 (-413 3808);
PAINT GREEN (-413 3808);
FORCEPROP 2 LAST CDS_LIB standard
J 0
(-475 3800);
DISPLAY INVISIBLE (-475 3800);
FORCEPROP 1 LAST BODY_TYPE PLUMBING
J 2
(-475 3850);
DISPLAY 0.872340 (-475 3850);
PAINT GREEN (-475 3850);
DISPLAY INVISIBLE (-475 3850);
FORCEPROP 1 LAST HDL_TAP TRUE
J 2
(-800 3675);
DISPLAY 0.872340 (-800 3675);
DISPLAY INVISIBLE (-800 3675);
FORCEPROP 1 LAST PATH I301
J 2
(-473 3800);
DISPLAY 0.872340 (-473 3800);
PAINT GREEN (-473 3800);
DISPLAY INVISIBLE (-473 3800);
FORCEADD TAP..1
R 2
(-475 3700);
FORCEPROP 3 LASTPIN (-425 3700) SIG_NAME DMI_CPU0_PCH_RX_C_DN<1>
J 0
(-415 3710);
DISPLAY 0.659574 (-415 3710);
PAINT MONO (-415 3710);
DISPLAY INVISIBLE (-415 3710);
FORCEPROP 1 LASTPIN (-425 3700) BN 1
J 2
(-413 3708);
DISPLAY 0.680851 (-413 3708);
PAINT GREEN (-413 3708);
FORCEPROP 2 LAST CDS_LIB standard
J 0
(-475 3700);
DISPLAY INVISIBLE (-475 3700);
FORCEPROP 1 LAST BODY_TYPE PLUMBING
J 2
(-475 3750);
DISPLAY 0.872340 (-475 3750);
PAINT GREEN (-475 3750);
DISPLAY INVISIBLE (-475 3750);
FORCEPROP 1 LAST HDL_TAP TRUE
J 2
(-800 3575);
DISPLAY 0.872340 (-800 3575);
DISPLAY INVISIBLE (-800 3575);
FORCEPROP 1 LAST PATH I302
J 2
(-473 3700);
DISPLAY 0.872340 (-473 3700);
PAINT GREEN (-473 3700);
DISPLAY INVISIBLE (-473 3700);
FORCEADD TAP..1
R 2
(-225 3500);
FORCEPROP 3 LASTPIN (-175 3500) SIG_NAME DMI_CPU0_PCH_RX_C_DP<6>
J 0
(-165 3510);
DISPLAY 0.659574 (-165 3510);
PAINT MONO (-165 3510);
DISPLAY INVISIBLE (-165 3510);
FORCEPROP 1 LASTPIN (-175 3500) BN 6
J 2
(-163 3508);
DISPLAY 0.680851 (-163 3508);
PAINT GREEN (-163 3508);
FORCEPROP 2 LAST CDS_LIB standard
J 0
(-225 3500);
DISPLAY INVISIBLE (-225 3500);
FORCEPROP 1 LAST BODY_TYPE PLUMBING
J 2
(-225 3550);
DISPLAY 0.872340 (-225 3550);
PAINT GREEN (-225 3550);
DISPLAY INVISIBLE (-225 3550);
FORCEPROP 1 LAST HDL_TAP TRUE
J 2
(-550 3375);
DISPLAY 0.872340 (-550 3375);
DISPLAY INVISIBLE (-550 3375);
FORCEPROP 1 LAST PATH I303
J 2
(-223 3500);
DISPLAY 0.872340 (-223 3500);
PAINT GREEN (-223 3500);
DISPLAY INVISIBLE (-223 3500);
FORCEADD TAP..1
R 2
(-225 3450);
FORCEPROP 3 LASTPIN (-175 3450) SIG_NAME DMI_CPU0_PCH_RX_C_DP<5>
J 0
(-165 3460);
DISPLAY 0.659574 (-165 3460);
PAINT MONO (-165 3460);
DISPLAY INVISIBLE (-165 3460);
FORCEPROP 1 LASTPIN (-175 3450) BN 5
J 2
(-163 3458);
DISPLAY 0.680851 (-163 3458);
PAINT GREEN (-163 3458);
FORCEPROP 2 LAST CDS_LIB standard
J 0
(-225 3450);
DISPLAY INVISIBLE (-225 3450);
FORCEPROP 1 LAST BODY_TYPE PLUMBING
J 2
(-225 3500);
DISPLAY 0.872340 (-225 3500);
PAINT GREEN (-225 3500);
DISPLAY INVISIBLE (-225 3500);
FORCEPROP 1 LAST HDL_TAP TRUE
J 2
(-550 3325);
DISPLAY 0.872340 (-550 3325);
DISPLAY INVISIBLE (-550 3325);
FORCEPROP 1 LAST PATH I304
J 2
(-223 3450);
DISPLAY 0.872340 (-223 3450);
PAINT GREEN (-223 3450);
DISPLAY INVISIBLE (-223 3450);
FORCEADD TAP..1
R 2
(-225 3400);
FORCEPROP 3 LASTPIN (-175 3400) SIG_NAME DMI_CPU0_PCH_RX_C_DP<4>
J 0
(-165 3410);
DISPLAY 0.659574 (-165 3410);
PAINT MONO (-165 3410);
DISPLAY INVISIBLE (-165 3410);
FORCEPROP 1 LASTPIN (-175 3400) BN 4
J 2
(-163 3408);
DISPLAY 0.680851 (-163 3408);
PAINT GREEN (-163 3408);
FORCEPROP 2 LAST CDS_LIB standard
J 0
(-225 3400);
DISPLAY INVISIBLE (-225 3400);
FORCEPROP 1 LAST BODY_TYPE PLUMBING
J 2
(-225 3450);
DISPLAY 0.872340 (-225 3450);
PAINT GREEN (-225 3450);
DISPLAY INVISIBLE (-225 3450);
FORCEPROP 1 LAST HDL_TAP TRUE
J 2
(-550 3275);
DISPLAY 0.872340 (-550 3275);
DISPLAY INVISIBLE (-550 3275);
FORCEPROP 1 LAST PATH I305
J 2
(-223 3400);
DISPLAY 0.872340 (-223 3400);
PAINT GREEN (-223 3400);
DISPLAY INVISIBLE (-223 3400);
FORCEADD TAP..1
R 2
(-225 3350);
FORCEPROP 3 LASTPIN (-175 3350) SIG_NAME DMI_CPU0_PCH_RX_C_DP<3>
J 0
(-165 3360);
DISPLAY 0.659574 (-165 3360);
PAINT MONO (-165 3360);
DISPLAY INVISIBLE (-165 3360);
FORCEPROP 1 LASTPIN (-175 3350) BN 3
J 2
(-163 3358);
DISPLAY 0.680851 (-163 3358);
PAINT GREEN (-163 3358);
FORCEPROP 2 LAST CDS_LIB standard
J 0
(-225 3350);
DISPLAY INVISIBLE (-225 3350);
FORCEPROP 1 LAST BODY_TYPE PLUMBING
J 2
(-225 3400);
DISPLAY 0.872340 (-225 3400);
PAINT GREEN (-225 3400);
DISPLAY INVISIBLE (-225 3400);
FORCEPROP 1 LAST HDL_TAP TRUE
J 2
(-550 3225);
DISPLAY 0.872340 (-550 3225);
DISPLAY INVISIBLE (-550 3225);
FORCEPROP 1 LAST PATH I306
J 2
(-223 3350);
DISPLAY 0.872340 (-223 3350);
PAINT GREEN (-223 3350);
DISPLAY INVISIBLE (-223 3350);
FORCEADD TAP..1
R 2
(-225 3250);
FORCEPROP 3 LASTPIN (-175 3250) SIG_NAME DMI_CPU0_PCH_RX_C_DP<1>
J 0
(-165 3260);
DISPLAY 0.659574 (-165 3260);
PAINT MONO (-165 3260);
DISPLAY INVISIBLE (-165 3260);
FORCEPROP 1 LASTPIN (-175 3250) BN 1
J 2
(-163 3258);
DISPLAY 0.680851 (-163 3258);
PAINT GREEN (-163 3258);
FORCEPROP 2 LAST CDS_LIB standard
J 0
(-225 3250);
DISPLAY INVISIBLE (-225 3250);
FORCEPROP 1 LAST BODY_TYPE PLUMBING
J 2
(-225 3300);
DISPLAY 0.872340 (-225 3300);
PAINT GREEN (-225 3300);
DISPLAY INVISIBLE (-225 3300);
FORCEPROP 1 LAST HDL_TAP TRUE
J 2
(-550 3125);
DISPLAY 0.872340 (-550 3125);
DISPLAY INVISIBLE (-550 3125);
FORCEPROP 1 LAST PATH I307
J 2
(-223 3250);
DISPLAY 0.872340 (-223 3250);
PAINT GREEN (-223 3250);
DISPLAY INVISIBLE (-223 3250);
FORCEADD TAP..1
(3400 3500);
FORCEPROP 3 LASTPIN (3350 3500) SIG_NAME DMI_CPU0_PCH_TX_DN<6>
J 0
(3360 3510);
DISPLAY 0.659574 (3360 3510);
PAINT MONO (3360 3510);
DISPLAY INVISIBLE (3360 3510);
FORCEPROP 1 LASTPIN (3350 3500) BN 6
J 0
(3338 3508);
DISPLAY 0.680851 (3338 3508);
PAINT GREEN (3338 3508);
FORCEPROP 2 LAST CDS_LIB standard
J 0
(3400 3500);
DISPLAY INVISIBLE (3400 3500);
FORCEPROP 1 LAST BODY_TYPE PLUMBING
J 0
(3400 3550);
DISPLAY 0.872340 (3400 3550);
PAINT GREEN (3400 3550);
DISPLAY INVISIBLE (3400 3550);
FORCEPROP 1 LAST HDL_TAP TRUE
J 0
(3725 3375);
DISPLAY 0.872340 (3725 3375);
DISPLAY INVISIBLE (3725 3375);
FORCEPROP 1 LAST PATH I308
J 0
(3398 3500);
DISPLAY 0.872340 (3398 3500);
PAINT GREEN (3398 3500);
DISPLAY INVISIBLE (3398 3500);
FORCEADD TAP..1
(3150 3950);
FORCEPROP 3 LASTPIN (3100 3950) SIG_NAME DMI_CPU0_PCH_TX_DP<6>
J 0
(3110 3960);
DISPLAY 0.659574 (3110 3960);
PAINT MONO (3110 3960);
DISPLAY INVISIBLE (3110 3960);
FORCEPROP 1 LASTPIN (3100 3950) BN 6
J 0
(3088 3958);
DISPLAY 0.680851 (3088 3958);
PAINT GREEN (3088 3958);
FORCEPROP 2 LAST CDS_LIB standard
J 0
(3150 3950);
DISPLAY INVISIBLE (3150 3950);
FORCEPROP 1 LAST BODY_TYPE PLUMBING
J 0
(3150 4000);
DISPLAY 0.872340 (3150 4000);
PAINT GREEN (3150 4000);
DISPLAY INVISIBLE (3150 4000);
FORCEPROP 1 LAST HDL_TAP TRUE
J 0
(3475 3825);
DISPLAY 0.872340 (3475 3825);
DISPLAY INVISIBLE (3475 3825);
FORCEPROP 1 LAST PATH I309
J 0
(3148 3950);
DISPLAY 0.872340 (3148 3950);
PAINT GREEN (3148 3950);
DISPLAY INVISIBLE (3148 3950);
FORCEADD TAP..1
(3150 3350);
FORCEPROP 3 LASTPIN (3100 3350) SIG_NAME DMI_CPU0_PCH_TX_DP<3>
J 0
(3110 3360);
DISPLAY 0.659574 (3110 3360);
PAINT MONO (3110 3360);
DISPLAY INVISIBLE (3110 3360);
FORCEPROP 1 LASTPIN (3100 3350) BN 3
J 0
(3088 3358);
DISPLAY 0.680851 (3088 3358);
PAINT GREEN (3088 3358);
FORCEPROP 2 LAST CDS_LIB standard
J 0
(3150 3350);
DISPLAY INVISIBLE (3150 3350);
FORCEPROP 1 LAST BODY_TYPE PLUMBING
J 0
(3150 3400);
DISPLAY 0.872340 (3150 3400);
PAINT GREEN (3150 3400);
DISPLAY INVISIBLE (3150 3400);
FORCEPROP 1 LAST HDL_TAP TRUE
J 0
(3475 3225);
DISPLAY 0.872340 (3475 3225);
DISPLAY INVISIBLE (3475 3225);
FORCEPROP 1 LAST PATH I310
J 0
(3148 3350);
DISPLAY 0.872340 (3148 3350);
PAINT GREEN (3148 3350);
DISPLAY INVISIBLE (3148 3350);
FORCEADD TAP..1
(3400 3800);
FORCEPROP 3 LASTPIN (3350 3800) SIG_NAME DMI_CPU0_PCH_TX_DN<3>
J 0
(3360 3810);
DISPLAY 0.659574 (3360 3810);
PAINT MONO (3360 3810);
DISPLAY INVISIBLE (3360 3810);
FORCEPROP 1 LASTPIN (3350 3800) BN 3
J 0
(3338 3808);
DISPLAY 0.680851 (3338 3808);
PAINT GREEN (3338 3808);
FORCEPROP 2 LAST CDS_LIB standard
J 0
(3400 3800);
DISPLAY INVISIBLE (3400 3800);
FORCEPROP 1 LAST BODY_TYPE PLUMBING
J 0
(3400 3850);
DISPLAY 0.872340 (3400 3850);
PAINT GREEN (3400 3850);
DISPLAY INVISIBLE (3400 3850);
FORCEPROP 1 LAST HDL_TAP TRUE
J 0
(3725 3675);
DISPLAY 0.872340 (3725 3675);
DISPLAY INVISIBLE (3725 3675);
FORCEPROP 1 LAST PATH I311
J 0
(3398 3800);
DISPLAY 0.872340 (3398 3800);
PAINT GREEN (3398 3800);
DISPLAY INVISIBLE (3398 3800);
FORCEADD QUANTA_TITLE_BLOCK_C..1
(6075 -1500);
FORCEPROP 0 LAST CDS_CON_LAST_MODIFIED Fri Aug 25 14:00:13 2023
J 0
(4190 -1485);
PAINT MONO (4190 -1485);
DISPLAY INVISIBLE (4190 -1485);
FORCEPROP 1 LAST CUSTOM_TXT_CDS <CON_LAST_MODIFIED>
J 0
(4190 -1485);
DISPLAY 0.978723 (4190 -1485);
FORCEPROP 2 LAST CUSTOM_TXT_CDS <XR_PAGE_TITLE>
J 0
(-1815 3750);
DISPLAY 0.638298 (-1815 3750);
PAINT PINK (-1815 3750);
DISPLAY INVISIBLE (-1815 3750);
FORCEPROP 2 LAST CUSTOM_TXT_CDS <Q_NUMBER>
J 0
(4672 -1397);
DISPLAY 1.212766 (4672 -1397);
FORCEPROP 1 LAST CUSTOM_TXT_CDS <NAME_2>
J 0
(2900 -1450);
FORCEPROP 1 LAST CUSTOM_TXT_CDS <NAME_1>
J 0
(2900 -1325);
FORCEPROP 1 LAST CUSTOM_TXT_CDS <Q_PROJ>
J 0
(3693 -1398);
DISPLAY 1.212766 (3693 -1398);
FORCEPROP 1 LAST CUSTOM_TXT_CDS <Q_REV>
J 0
(5891 -1397);
DISPLAY 1.212766 (5891 -1397);
FORCEPROP 1 LAST CUSTOM_TXT_CDS <CON_PAGE_NUM> OF <CON_TOTAL_PAGES>
J 0
(5629 -1482);
DISPLAY 0.978723 (5629 -1482);
FORCEPROP 1 LAST Q_TITLE SPR CPU0 - DMI (16 OF 30)
J 0
(-3291 -1474);
DISPLAY 1.957447 (-3291 -1474);
PAINT GREEN (-3291 -1474);
FORCEPROP 1 LAST Q_DEPT 
J 1
(2312 -1451);
DISPLAY 1.957447 (2312 -1451);
PAINT GREEN (2312 -1451);
FORCEPROP 2 LAST PAGE_BORDER TRUE
J 0
(-1815 3750);
DISPLAY 0.638298 (-1815 3750);
PAINT PINK (-1815 3750);
DISPLAY INVISIBLE (-1815 3750);
FORCEPROP 1 LAST CDS_LMAN_SYM_OUTLINE -9475,6775,100,-125
J 0
(6075 -1500);
DISPLAY 0.468085 (6075 -1500);
PAINT GREEN (6075 -1500);
DISPLAY INVISIBLE (6075 -1500);
FORCEPROP 2 LAST CDS_LIB pure_quanta
J 0
(6075 -1500);
PAINT MONO (6075 -1500);
DISPLAY INVISIBLE (6075 -1500);
FORCEPROP 2 LAST CDS_XR_PAGE_TITLE CR-28 : @S9S_MB_2U_LIB.S9S_MB_2U(SCH_1):PAGE28
J 0
(-1815 3750);
DISPLAY 0.638298 (-1815 3750);
PAINT PINK (-1815 3750);
DISPLAY INVISIBLE (-1815 3750);
FORCEPROP 1 LAST COMMENT_BODY TRUE
J 0
(6087 -1513);
DISPLAY 0.978723 (6087 -1513);
PAINT GREEN (6087 -1513);
DISPLAY INVISIBLE (6087 -1513);
WIRE 17 -1 (3450 3725)(3450 3675);
WIRE 17 -1 (3450 3775)(3450 3725);
WIRE 17 -1 (3450 3525)(3450 3675);
WIRE 17 -1 (3450 3475)(3450 3525);
WIRE 17 -1 (3450 3825)(3450 3775);
WIRE 17 -1 (3450 4025)(3450 3825);
WIRE 17 -1 (3450 3425)(3450 3475);
WIRE 17 -1 (3450 4050)(3450 4025);
WIRE 17 -1 (3450 4050)(4450 4050);
FORCEPROP 2 LAST SIG_NAME DMI_CPU0_PCH_TX_DN<7:0>
J 0
(3590 4060);
DISPLAY 0.680851 (3590 4060);
PAINT WHITE (3590 4060);
WIRE 17 -1 (3200 3875)(3200 3925);
WIRE 17 -1 (3200 3575)(3200 3875);
WIRE 17 -1 (3200 3975)(3200 3925);
WIRE 17 -1 (3200 4100)(3200 3975);
WIRE 17 -1 (3200 3575)(3200 3375);
WIRE 17 -1 (3200 3375)(3200 3325);
WIRE 17 -1 (3200 4100)(4450 4100);
FORCEPROP 2 LAST SIG_NAME DMI_CPU0_PCH_TX_DP<7:0>
J 0
(3590 4110);
DISPLAY 0.680851 (3590 4110);
PAINT WHITE (3590 4110);
WIRE 17 -1 (3200 3275)(3200 3225);
WIRE 17 -1 (3200 3325)(3200 3275);
WIRE 17 -1 (-275 3775)(-275 3675);
WIRE 17 -1 (-275 4025)(-275 3775);
WIRE 17 -1 (-275 3675)(-275 3525);
WIRE 17 -1 (-275 3525)(-275 3475);
WIRE 17 -1 (-275 4150)(-275 4025);
WIRE 17 -1 (-1700 4150)(-275 4150);
FORCEPROP 2 LAST SIG_NAME DMI_CPU0_PCH_RX_C_DP<7:0>
J 0
(-1585 4160);
DISPLAY 0.680851 (-1585 4160);
PAINT WHITE (-1585 4160);
WIRE 17 -1 (-525 3825)(-525 3725);
WIRE 17 -1 (-525 3875)(-525 3825);
WIRE 17 -1 (-525 3725)(-525 3575);
WIRE 17 -1 (-525 3575)(-525 3325);
WIRE 17 -1 (-525 3925)(-525 3875);
WIRE 17 -1 (-525 3975)(-525 3925);
WIRE 17 -1 (-525 3225)(-525 3325);
WIRE 17 -1 (-525 4100)(-525 3975);
WIRE 17 -1 (-1700 4100)(-525 4100);
FORCEPROP 2 LAST SIG_NAME DMI_CPU0_PCH_RX_C_DN<7:0>
J 0
(-1585 4110);
DISPLAY 0.680851 (-1585 4110);
PAINT WHITE (-1585 4110);
WIRE 17 -1 (-275 3375)(-275 3275);
WIRE 17 -1 (-275 3425)(-275 3375);
WIRE 17 -1 (-275 3475)(-275 3425);
WIRE 16 -1 (-425 3550)(275 3550);
WIRE 16 -1 (-175 3500)(275 3500);
WIRE 16 -1 (-175 3450)(275 3450);
WIRE 16 -1 (-175 3400)(275 3400);
WIRE 16 -1 (-175 3350)(275 3350);
WIRE 16 -1 (-425 3300)(275 3300);
WIRE 16 -1 (-175 3250)(275 3250);
WIRE 16 -1 (-425 3200)(275 3200);
WIRE 16 -1 (-175 4000)(275 4000);
WIRE 16 -1 (-425 3950)(275 3950);
WIRE 16 -1 (-425 3900)(275 3900);
WIRE 16 -1 (275 3850)(-425 3850);
WIRE 16 -1 (-425 3800)(275 3800);
WIRE 16 -1 (-175 3750)(275 3750);
WIRE 16 -1 (275 3700)(-425 3700);
WIRE 16 -1 (-175 3650)(275 3650);
WIRE 16 -1 (2675 3550)(3100 3550);
WIRE 16 -1 (2675 3500)(3350 3500);
FORCEPROP 0 LAST $PNN DMI_CPU0_PCH_TX_DP<3>
J 0
(3225 3500);
DISPLAY INVISIBLE (3225 3500);
WIRE 16 -1 (2675 3450)(3350 3450);
WIRE 16 -1 (2675 3400)(3350 3400);
WIRE 16 -1 (2675 3350)(3100 3350);
WIRE 16 -1 (2675 3300)(3100 3300);
WIRE 16 -1 (2675 3250)(3100 3250);
WIRE 16 -1 (2675 3200)(3100 3200);
WIRE 16 -1 (2675 4000)(3350 4000);
WIRE 16 -1 (2675 3950)(3100 3950);
WIRE 16 -1 (2675 3900)(3100 3900);
WIRE 16 -1 (2675 3850)(3100 3850);
WIRE 16 -1 (2675 3800)(3350 3800);
FORCEPROP 0 LAST $PNN DMI_CPU0_PCH_TX_DP<6>
J 0
(3225 3800);
DISPLAY INVISIBLE (3225 3800);
WIRE 16 -1 (2675 3750)(3350 3750);
WIRE 16 -1 (2675 3700)(3350 3700);
WIRE 16 -1 (2675 3650)(3350 3650);
QUIT
